FILE_TYPE = MULTI_PHYS_TABLE;

PART 'SCONN13_502280130CV01'

{========================================================================================}
:VALUE                     | PART_TYPE | MATERIAL | PART_NUMBER    = STANDARD | LIFECYCLE     | PART_NUMBER   | JEDEC_TYPE         | DESCRIPTION                            | MANUFTR | MANUF_PN          | RD_CMPLS_LVL | CMPLS_LVL | CLASS | DIP_SMD | FROM_PJ   | DATA                      | FP_ECN | EE_CHECK_LIST | CREATOR | CREATEDAY  | PSL | STATUS | ESD_CDM | ESD_HBM | ESD_MM | MSD  | PIN_LENGTH_LONG_PIN | PIN_LENGTH_SHORT_PIN ;
{========================================================================================}
 'SCONN13_50228-0130C-V01' | 'SMLF'    | 'IO'     | 'DFHD13MS080'(!) = ''       | ''               | 'DFHD13MS080' |'CON_13S1H2S_P1XA'| 'CONN SMD HEADER 13P 1R MS(P1.0,H4.3)' | 'ACS'   | '50228-0130C-V01' | 'EP(V1)'     | ''        | 'IO'  | ''      | 'S5C-YAN' | 'ACS_50228-0130C-V01.pdf' | ''     | ''            | ''      | '20180315' | ''  | ''     | 'NA'    | 'NA'    | 'NA'   | 'NA' | '0 MILS'            | '0 MILS'            
 'SCONN13_50228-0130C-V01' | 'SMLF'    | 'EMPTY'  | 'DFHD13MS080'(!) = ''       | ''               | 'DFHD13MS080' |'CON_13S1H2S_P1XA'| 'CONN SMD HEADER 13P 1R MS(P1.0,H4.3)' | 'ACS'   | '50228-0130C-V01' | 'EP(V1)'     | ''        | 'IO'  | ''      | 'S5C-YAN' | 'ACS_50228-0130C-V01.pdf' | ''     | ''            | ''      | '20180315' | ''  | ''     | 'NA'    | 'NA'    | 'NA'   | 'NA' | '0 MILS'            | '0 MILS'            

END_PART

END.

